FILE_TYPE=LIBRARY_PARTS;
primitive 'NPN','NPN_SM','NPN_SMLF';
  pin
    'B':
      PIN_NUMBER='(1)';
      PINUSE='UNSPEC';
      NO_LOAD_CHECK='BOTH';
      NO_IO_CHECK='BOTH';
      ALLOW_CONNECT='TRUE';
    'C':
      PIN_NUMBER='(3)';
      PINUSE='UNSPEC';
      NO_LOAD_CHECK='BOTH';
      NO_IO_CHECK='BOTH';
      ALLOW_CONNECT='TRUE';
    'E':
      PIN_NUMBER='(2)';
      PINUSE='UNSPEC';
      NO_LOAD_CHECK='BOTH';
      NO_IO_CHECK='BOTH';
      ALLOW_CONNECT='TRUE';
  end_pin;
  body
    PART_NAME='NPN';
    PHYS_DES_PREFIX='Q';
  end_body;
end_primitive;
primitive 'NPN_SOT369','NPN_SOT369LF','NPN_TO252C';
  pin
    'B':
      PIN_NUMBER='(1)';
      PINUSE='UNSPEC';
      NO_LOAD_CHECK='BOTH';
      NO_IO_CHECK='BOTH';
      ALLOW_CONNECT='TRUE';
    'C':
      PIN_NUMBER='(2)';
      PINUSE='UNSPEC';
      NO_LOAD_CHECK='BOTH';
      NO_IO_CHECK='BOTH';
      ALLOW_CONNECT='TRUE';
    'E':
      PIN_NUMBER='(3)';
      PINUSE='UNSPEC';
      NO_LOAD_CHECK='BOTH';
      NO_IO_CHECK='BOTH';
      ALLOW_CONNECT='TRUE';
  end_pin;
  body
    PART_NAME='NPN';
    PHYS_DES_PREFIX='Q';
  end_body;
end_primitive;
primitive 'NPN_E1B2LF';
  pin
    'B':
      PIN_NUMBER='(2)';
      PINUSE='UNSPEC';
      NO_LOAD_CHECK='BOTH';
      NO_IO_CHECK='BOTH';
      ALLOW_CONNECT='TRUE';
    'C':
      PIN_NUMBER='(3)';
      PINUSE='UNSPEC';
      NO_LOAD_CHECK='BOTH';
      NO_IO_CHECK='BOTH';
      ALLOW_CONNECT='TRUE';
    'E':
      PIN_NUMBER='(1)';
      PINUSE='UNSPEC';
      NO_LOAD_CHECK='BOTH';
      NO_IO_CHECK='BOTH';
      ALLOW_CONNECT='TRUE';
  end_pin;
  body
    PART_NAME='NPN';
    PHYS_DES_PREFIX='Q';
  end_body;
end_primitive;
primitive 'NPN_SOT369C','NPN_SOT369CLF';
  pin
    'B':
      PIN_NUMBER='(1)';
      PINUSE='UNSPEC';
      NO_LOAD_CHECK='BOTH';
      NO_IO_CHECK='BOTH';
      ALLOW_CONNECT='TRUE';
    'C':
      PIN_NUMBER='(3)';
      PINUSE='UNSPEC';
      NO_LOAD_CHECK='BOTH';
      NO_IO_CHECK='BOTH';
      ALLOW_CONNECT='TRUE';
    'E':
      PIN_NUMBER='(2)';
      PINUSE='UNSPEC';
      NO_LOAD_CHECK='BOTH';
      NO_IO_CHECK='BOTH';
      ALLOW_CONNECT='TRUE';
  end_pin;
  body
    PART_NAME='NPN';
    PHYS_DES_PREFIX='Q';
  end_body;
end_primitive;
primitive 'NPN_THLF';
  pin
    'B':
      PIN_NUMBER='(3)';
      PINUSE='UNSPEC';
      NO_LOAD_CHECK='Both';
      NO_IO_CHECK='Both';
      ALLOW_CONNECT='TRUE';
    'C':
      PIN_NUMBER='(2)';
      PINUSE='UNSPEC';
      NO_LOAD_CHECK='Both';
      NO_IO_CHECK='Both';
      ALLOW_CONNECT='TRUE';
    'E':
      PIN_NUMBER='(1)';
      PINUSE='UNSPEC';
      NO_LOAD_CHECK='Both';
      NO_IO_CHECK='Both';
      ALLOW_CONNECT='TRUE';
  end_pin;
  body
    PART_NAME='NPN';
    PHYS_DES_PREFIX='Q';
    CLASS='IC';
  end_body;
end_primitive;
END.
